FILE_TYPE = CONNECTIVITY;
{Allegro Design Entry HDL 17.4-2019 S026 (4007227) 1/17/2022}
"PAGE_NUMBER" = 366;
0"NC";
END.
